(kicad_pcb
	(version 20260206)
	(generator "pcbnew")
	(generator_version "10.0")
	(general
		(thickness 1.6)
		(legacy_teardrops no)
	)
	(paper "A4")
	(title_block
		(title "12092022_DA0F0TMDCD0_F0T_Management_Board_D_brd_V3_OCP.brd")
		(comment 1 "Grand Teton / footprints 690-695 of 1440")
	)
	(layers
		(0 "F.Cu" signal "TOP")
		(4 "In1.Cu" signal "GND")
		(6 "In2.Cu" signal "IN1")
		(8 "In3.Cu" signal "GND1")
		(10 "In4.Cu" signal "IN2")
		(12 "In5.Cu" signal "VCC")
		(14 "In6.Cu" signal "VCC1")
		(16 "In7.Cu" signal "IN3")
		(18 "In8.Cu" signal "GND2")
		(20 "In9.Cu" signal "IN4")
		(22 "In10.Cu" signal "GND3")
		(2 "B.Cu" signal "BOTTOM")
		(9 "F.Adhes" user "F.Adhesive")
		(11 "B.Adhes" user "B.Adhesive")
		(13 "F.Paste" user "Package Geometry/Pastemask Top")
		(15 "B.Paste" user "Package Geometry/Pastemask Bottom")
		(5 "F.SilkS" user "Ref Des/Silkscreen Top")
		(7 "B.SilkS" user "Ref Des/Silkscreen Bottom")
		(1 "F.Mask" user "Board Geometry/Soldermask Top")
		(3 "B.Mask" user "Board Geometry/Soldermask Bottom")
		(17 "Dwgs.User" user "User.Drawings")
		(19 "Cmts.User" user "User.Comments")
		(21 "Eco1.User" user "User.Eco1")
		(23 "Eco2.User" user "User.Eco2")
		(25 "Edge.Cuts" user "Board Geometry/Outline")
		(27 "Margin" user)
		(31 "F.CrtYd" user "Package Geometry/Place Bound Top")
		(29 "B.CrtYd" user "Package Geometry/Place Bound Bottom")
		(35 "F.Fab" user "Ref Des/Assembly Top")
		(33 "B.Fab" user "Ref Des/Assembly Bottom")
	)
	(footprint ""
		(layer "F.Cu")
		(at 63.246 -79.629)
		(property "Reference" "R506"
			(at 0 0 0)
			(layer "F.SilkS")
			(hide yes)
			(effects
				(font
					(size 1.27 1.27)
				)
			)
		)
		(property "Value" ""
			(at 0 0 0)
			(layer "F.Fab")
			(effects
				(font
					(size 1.27 1.27)
				)
			)
		)
		(duplicate_pad_numbers_are_jumpers no)
		(fp_line
			(start -0.7874 -0.4064)
			(end 0.7874 -0.4064)
			(stroke
				(width 0.1524)
				(type default)
			)
			(layer "F.SilkS")
		)
		(fp_line
			(start -0.7874 0.4064)
			(end -0.7874 -0.4064)
			(stroke
				(width 0.1524)
				(type default)
			)
			(layer "F.SilkS")
		)
		(fp_line
			(start 0.7874 -0.4064)
			(end 0.7874 0.4064)
			(stroke
				(width 0.1524)
				(type default)
			)
			(layer "F.SilkS")
		)
		(fp_line
			(start 0.7874 0.4064)
			(end -0.7874 0.4064)
			(stroke
				(width 0.1524)
				(type default)
			)
			(layer "F.SilkS")
		)
		(fp_line
			(start -0.67945 -0.305054)
			(end -0.12065 -0.305054)
			(stroke
				(width 0.1)
				(type default)
			)
			(layer "F.Fab")
		)
		(fp_line
			(start -0.67945 0.3048)
			(end -0.67945 -0.305054)
			(stroke
				(width 0.1)
				(type default)
			)
			(layer "F.Fab")
		)
		(fp_line
			(start -0.12065 -0.305054)
			(end -0.12065 -0.2794)
			(stroke
				(width 0.1)
				(type default)
			)
			(layer "F.Fab")
		)
		(fp_line
			(start -0.12065 -0.2794)
			(end 0.12065 -0.2794)
			(stroke
				(width 0.1)
				(type default)
			)
			(layer "F.Fab")
		)
		(fp_line
			(start -0.12065 0.2794)
			(end -0.12065 0.3048)
			(stroke
				(width 0.1)
				(type default)
			)
			(layer "F.Fab")
		)
		(fp_line
			(start -0.12065 0.3048)
			(end -0.67945 0.3048)
			(stroke
				(width 0.1)
				(type default)
			)
			(layer "F.Fab")
		)
		(fp_line
			(start 0.120396 0.2794)
			(end -0.12065 0.2794)
			(stroke
				(width 0.1)
				(type default)
			)
			(layer "F.Fab")
		)
		(fp_line
			(start 0.120396 0.3048)
			(end 0.120396 0.2794)
			(stroke
				(width 0.1)
				(type default)
			)
			(layer "F.Fab")
		)
		(fp_line
			(start 0.12065 -0.3048)
			(end 0.67945 -0.3048)
			(stroke
				(width 0.1)
				(type default)
			)
			(layer "F.Fab")
		)
		(fp_line
			(start 0.12065 -0.2794)
			(end 0.12065 -0.3048)
			(stroke
				(width 0.1)
				(type default)
			)
			(layer "F.Fab")
		)
		(fp_line
			(start 0.67945 -0.3048)
			(end 0.67945 0.3048)
			(stroke
				(width 0.1)
				(type default)
			)
			(layer "F.Fab")
		)
		(fp_line
			(start 0.67945 0.3048)
			(end 0.120396 0.3048)
			(stroke
				(width 0.1)
				(type default)
			)
			(layer "F.Fab")
		)
		(pad "1" smd circle
			(at -0.40005 0)
			(size 0 0)
			(layers "F.Cu" "F.Mask" "F.Paste")
			(net "FM_BMC_DEBUG_SW_N")
		)
		(pad "2" smd circle
			(at 0.40005 0)
			(size 0 0)
			(layers "F.Cu" "F.Mask" "F.Paste")
			(net "GND")
		)
	)
	(footprint ""
		(layer "F.Cu")
		(at 44.196 -67.7672)
		(property "Reference" "D8"
			(at -3.470656 -0.119634 0)
			(unlocked yes)
			(layer "F.SilkS")
			(effects
				(font
					(size 0.7874 0.5842)
					(thickness 0.1524)
				)
				(justify left)
			)
		)
		(property "Value" ""
			(at 0 0 0)
			(layer "F.Fab")
			(effects
				(font
					(size 1.27 1.27)
				)
			)
		)
		(duplicate_pad_numbers_are_jumpers no)
		(fp_line
			(start -1.3208 -0.5588)
			(end 1.3208 -0.5588)
			(stroke
				(width 0.1524)
				(type default)
			)
			(layer "F.SilkS")
		)
		(fp_line
			(start -1.3208 0.5588)
			(end -1.3208 -0.5588)
			(stroke
				(width 0.1524)
				(type default)
			)
			(layer "F.SilkS")
		)
		(fp_line
			(start 1.3208 -0.5588)
			(end 1.3208 0.5588)
			(stroke
				(width 0.1524)
				(type default)
			)
			(layer "F.SilkS")
		)
		(fp_line
			(start 1.3208 0.5588)
			(end -1.3208 0.5588)
			(stroke
				(width 0.1524)
				(type default)
			)
			(layer "F.SilkS")
		)
		(fp_line
			(start 1.4732 -0.5588)
			(end 1.4732 0.5588)
			(stroke
				(width 0.1524)
				(type default)
			)
			(layer "F.SilkS")
		)
		(fp_line
			(start 1.6256 0.5588)
			(end 1.6256 -0.5588)
			(stroke
				(width 0.1524)
				(type default)
			)
			(layer "F.SilkS")
		)
		(fp_line
			(start 1.778 -0.5588)
			(end 1.3208 -0.5588)
			(stroke
				(width 0.1524)
				(type default)
			)
			(layer "F.SilkS")
		)
		(fp_line
			(start 1.778 -0.5588)
			(end 1.778 0.5588)
			(stroke
				(width 0.1524)
				(type default)
			)
			(layer "F.SilkS")
		)
		(fp_line
			(start 1.778 0.5588)
			(end 1.3208 0.5588)
			(stroke
				(width 0.1524)
				(type default)
			)
			(layer "F.SilkS")
		)
		(fp_line
			(start -1.235964 -0.508)
			(end -1.235964 0.508)
			(stroke
				(width 0.1)
				(type default)
			)
			(layer "F.Fab")
		)
		(fp_line
			(start -1.235964 0.508)
			(end -1.1684 0.508)
			(stroke
				(width 0.1)
				(type default)
			)
			(layer "F.Fab")
		)
		(fp_line
			(start -1.1684 -0.508)
			(end -1.235964 -0.508)
			(stroke
				(width 0.1)
				(type default)
			)
			(layer "F.Fab")
		)
		(fp_line
			(start -1.1684 0.508)
			(end 1.1684 0.508)
			(stroke
				(width 0.1)
				(type default)
			)
			(layer "F.Fab")
		)
		(fp_line
			(start 1.1684 -0.508)
			(end -1.1684 -0.508)
			(stroke
				(width 0.1)
				(type default)
			)
			(layer "F.Fab")
		)
		(fp_line
			(start 1.1684 0.508)
			(end 1.236726 0.508)
			(stroke
				(width 0.1)
				(type default)
			)
			(layer "F.Fab")
		)
		(fp_line
			(start 1.236726 -0.508)
			(end 1.1684 -0.508)
			(stroke
				(width 0.1)
				(type default)
			)
			(layer "F.Fab")
		)
		(fp_line
			(start 1.236726 0.508)
			(end 1.236726 -0.508)
			(stroke
				(width 0.1)
				(type default)
			)
			(layer "F.Fab")
		)
		(fp_text user "+"
			(at -2.286 -1.06045 0)
			(unlocked yes)
			(layer "F.SilkS")
			(effects
				(font
					(size 1.905 1.4224)
					(thickness 0.1524)
				)
				(justify left)
			)
		)
		(fp_text user "-"
			(at 2.00025 0.7112 90)
			(unlocked yes)
			(layer "F.SilkS")
			(effects
				(font
					(size 1.905 1.4224)
					(thickness 0.1524)
				)
				(justify left)
			)
		)
		(fp_text user "+"
			(at -2.5654 -0.24765 0)
			(unlocked yes)
			(layer "F.Fab")
			(effects
				(font
					(size 1.905 1.4224)
					(thickness 0.1524)
				)
				(justify left)
			)
		)
		(fp_text user "-"
			(at 1.524 -0.24765 0)
			(unlocked yes)
			(layer "F.Fab")
			(effects
				(font
					(size 1.905 1.4224)
					(thickness 0.1524)
				)
				(justify left)
			)
		)
		(pad "A" smd rect
			(at -0.750062 0)
			(size 0.8128 0.8128)
			(layers "F.Cu" "F.Mask" "F.Paste")
			(net "BMC_HEARTBEAT_R_N")
		)
		(pad "C" smd rect
			(at 0.750062 0)
			(size 0.8128 0.8128)
			(layers "F.Cu" "F.Mask" "F.Paste")
			(net "BMC_HEARTBEAT_N")
		)
	)
	(footprint ""
		(layer "F.Cu")
		(at 12.319 -83.312 180)
		(property "Reference" "R439"
			(at 0 0 180)
			(layer "F.SilkS")
			(hide yes)
			(effects
				(font
					(size 1.27 1.27)
				)
			)
		)
		(property "Value" ""
			(at 0 0 180)
			(layer "F.Fab")
			(effects
				(font
					(size 1.27 1.27)
				)
			)
		)
		(duplicate_pad_numbers_are_jumpers no)
		(fp_line
			(start 0.7874 0.4064)
			(end -0.7874 0.4064)
			(stroke
				(width 0.1524)
				(type default)
			)
			(layer "F.SilkS")
		)
		(fp_line
			(start 0.7874 -0.4064)
			(end 0.7874 0.4064)
			(stroke
				(width 0.1524)
				(type default)
			)
			(layer "F.SilkS")
		)
		(fp_line
			(start -0.7874 0.4064)
			(end -0.7874 -0.4064)
			(stroke
				(width 0.1524)
				(type default)
			)
			(layer "F.SilkS")
		)
		(fp_line
			(start -0.7874 -0.4064)
			(end 0.7874 -0.4064)
			(stroke
				(width 0.1524)
				(type default)
			)
			(layer "F.SilkS")
		)
		(fp_line
			(start 0.67945 0.3048)
			(end 0.120396 0.3048)
			(stroke
				(width 0.1)
				(type default)
			)
			(layer "F.Fab")
		)
		(fp_line
			(start 0.67945 -0.3048)
			(end 0.67945 0.3048)
			(stroke
				(width 0.1)
				(type default)
			)
			(layer "F.Fab")
		)
		(fp_line
			(start 0.12065 -0.2794)
			(end 0.12065 -0.3048)
			(stroke
				(width 0.1)
				(type default)
			)
			(layer "F.Fab")
		)
		(fp_line
			(start 0.12065 -0.3048)
			(end 0.67945 -0.3048)
			(stroke
				(width 0.1)
				(type default)
			)
			(layer "F.Fab")
		)
		(fp_line
			(start 0.120396 0.3048)
			(end 0.120396 0.2794)
			(stroke
				(width 0.1)
				(type default)
			)
			(layer "F.Fab")
		)
		(fp_line
			(start 0.120396 0.2794)
			(end -0.12065 0.2794)
			(stroke
				(width 0.1)
				(type default)
			)
			(layer "F.Fab")
		)
		(fp_line
			(start -0.12065 0.3048)
			(end -0.67945 0.3048)
			(stroke
				(width 0.1)
				(type default)
			)
			(layer "F.Fab")
		)
		(fp_line
			(start -0.12065 0.2794)
			(end -0.12065 0.3048)
			(stroke
				(width 0.1)
				(type default)
			)
			(layer "F.Fab")
		)
		(fp_line
			(start -0.12065 -0.2794)
			(end 0.12065 -0.2794)
			(stroke
				(width 0.1)
				(type default)
			)
			(layer "F.Fab")
		)
		(fp_line
			(start -0.12065 -0.305054)
			(end -0.12065 -0.2794)
			(stroke
				(width 0.1)
				(type default)
			)
			(layer "F.Fab")
		)
		(fp_line
			(start -0.67945 0.3048)
			(end -0.67945 -0.305054)
			(stroke
				(width 0.1)
				(type default)
			)
			(layer "F.Fab")
		)
		(fp_line
			(start -0.67945 -0.305054)
			(end -0.12065 -0.305054)
			(stroke
				(width 0.1)
				(type default)
			)
			(layer "F.Fab")
		)
		(pad "1" smd circle
			(at -0.40005 0 180)
			(size 0 0)
			(layers "F.Cu" "F.Mask" "F.Paste")
			(net "FM_PECI_SEL_N")
		)
		(pad "2" smd circle
			(at 0.40005 0 180)
			(size 0 0)
			(layers "F.Cu" "F.Mask" "F.Paste")
			(net "FM_PECI_SEL_R_N")
		)
	)
	(footprint ""
		(layer "F.Cu")
		(at 69.0626 -108.0262 -90)
		(property "Reference" "R594"
			(at 0 0 270)
			(layer "F.SilkS")
			(hide yes)
			(effects
				(font
					(size 1.27 1.27)
				)
			)
		)
		(property "Value" ""
			(at 0 0 270)
			(layer "F.Fab")
			(effects
				(font
					(size 1.27 1.27)
				)
			)
		)
		(duplicate_pad_numbers_are_jumpers no)
		(fp_line
			(start -0.7874 0.4064)
			(end -0.7874 -0.4064)
			(stroke
				(width 0.1524)
				(type default)
			)
			(layer "F.SilkS")
		)
		(fp_line
			(start 0.7874 0.4064)
			(end -0.7874 0.4064)
			(stroke
				(width 0.1524)
				(type default)
			)
			(layer "F.SilkS")
		)
		(fp_line
			(start -0.7874 -0.4064)
			(end 0.7874 -0.4064)
			(stroke
				(width 0.1524)
				(type default)
			)
			(layer "F.SilkS")
		)
		(fp_line
			(start 0.7874 -0.4064)
			(end 0.7874 0.4064)
			(stroke
				(width 0.1524)
				(type default)
			)
			(layer "F.SilkS")
		)
		(fp_line
			(start -0.67945 0.3048)
			(end -0.67945 -0.305054)
			(stroke
				(width 0.1)
				(type default)
			)
			(layer "F.Fab")
		)
		(fp_line
			(start -0.12065 0.3048)
			(end -0.67945 0.3048)
			(stroke
				(width 0.1)
				(type default)
			)
			(layer "F.Fab")
		)
		(fp_line
			(start 0.120396 0.3048)
			(end 0.120396 0.2794)
			(stroke
				(width 0.1)
				(type default)
			)
			(layer "F.Fab")
		)
		(fp_line
			(start 0.67945 0.3048)
			(end 0.120396 0.3048)
			(stroke
				(width 0.1)
				(type default)
			)
			(layer "F.Fab")
		)
		(fp_line
			(start -0.12065 0.2794)
			(end -0.12065 0.3048)
			(stroke
				(width 0.1)
				(type default)
			)
			(layer "F.Fab")
		)
		(fp_line
			(start 0.120396 0.2794)
			(end -0.12065 0.2794)
			(stroke
				(width 0.1)
				(type default)
			)
			(layer "F.Fab")
		)
		(fp_line
			(start -0.12065 -0.2794)
			(end 0.12065 -0.2794)
			(stroke
				(width 0.1)
				(type default)
			)
			(layer "F.Fab")
		)
		(fp_line
			(start 0.12065 -0.2794)
			(end 0.12065 -0.3048)
			(stroke
				(width 0.1)
				(type default)
			)
			(layer "F.Fab")
		)
		(fp_line
			(start 0.12065 -0.3048)
			(end 0.67945 -0.3048)
			(stroke
				(width 0.1)
				(type default)
			)
			(layer "F.Fab")
		)
		(fp_line
			(start 0.67945 -0.3048)
			(end 0.67945 0.3048)
			(stroke
				(width 0.1)
				(type default)
			)
			(layer "F.Fab")
		)
		(fp_line
			(start -0.67945 -0.305054)
			(end -0.12065 -0.305054)
			(stroke
				(width 0.1)
				(type default)
			)
			(layer "F.Fab")
		)
		(fp_line
			(start -0.12065 -0.305054)
			(end -0.12065 -0.2794)
			(stroke
				(width 0.1)
				(type default)
			)
			(layer "F.Fab")
		)
		(pad "1" smd circle
			(at -0.40005 0 270)
			(size 0 0)
			(layers "F.Cu" "F.Mask" "F.Paste")
			(net "SPI_TPM_CS_N")
		)
		(pad "2" smd circle
			(at 0.40005 0 270)
			(size 0 0)
			(layers "F.Cu" "F.Mask" "F.Paste")
			(net "SPI_TPM_CS_R_N")
		)
	)
	(footprint ""
		(layer "F.Cu")
		(at 75.646534 -31.764986 -90)
		(property "Reference" "D6"
			(at 4.129786 -8.123936 90)
			(unlocked yes)
			(layer "F.SilkS")
			(effects
				(font
					(size 0.7874 0.5842)
					(thickness 0.1524)
				)
				(justify left)
			)
		)
		(property "Value" ""
			(at 0 0 270)
			(layer "F.Fab")
			(effects
				(font
					(size 1.27 1.27)
				)
			)
		)
		(duplicate_pad_numbers_are_jumpers no)
		(fp_line
			(start -1.3208 0.5588)
			(end -1.3208 -0.5588)
			(stroke
				(width 0.1524)
				(type default)
			)
			(layer "F.SilkS")
		)
		(fp_line
			(start 1.3208 0.5588)
			(end -1.3208 0.5588)
			(stroke
				(width 0.1524)
				(type default)
			)
			(layer "F.SilkS")
		)
		(fp_line
			(start 1.6256 0.5588)
			(end 1.6256 -0.5588)
			(stroke
				(width 0.1524)
				(type default)
			)
			(layer "F.SilkS")
		)
		(fp_line
			(start 1.778 0.5588)
			(end 1.3208 0.5588)
			(stroke
				(width 0.1524)
				(type default)
			)
			(layer "F.SilkS")
		)
		(fp_line
			(start -1.3208 -0.5588)
			(end 1.3208 -0.5588)
			(stroke
				(width 0.1524)
				(type default)
			)
			(layer "F.SilkS")
		)
		(fp_line
			(start 1.3208 -0.5588)
			(end 1.3208 0.5588)
			(stroke
				(width 0.1524)
				(type default)
			)
			(layer "F.SilkS")
		)
		(fp_line
			(start 1.4732 -0.5588)
			(end 1.4732 0.5588)
			(stroke
				(width 0.1524)
				(type default)
			)
			(layer "F.SilkS")
		)
		(fp_line
			(start 1.778 -0.5588)
			(end 1.778 0.5588)
			(stroke
				(width 0.1524)
				(type default)
			)
			(layer "F.SilkS")
		)
		(fp_line
			(start 1.778 -0.5588)
			(end 1.3208 -0.5588)
			(stroke
				(width 0.1524)
				(type default)
			)
			(layer "F.SilkS")
		)
		(fp_line
			(start -0.8001 0.40005)
			(end -0.8001 -0.40005)
			(stroke
				(width 0.1)
				(type default)
			)
			(layer "F.Fab")
		)
		(fp_line
			(start 0.8001 0.40005)
			(end -0.8001 0.40005)
			(stroke
				(width 0.1)
				(type default)
			)
			(layer "F.Fab")
		)
		(fp_line
			(start -0.8001 -0.40005)
			(end 0.8001 -0.40005)
			(stroke
				(width 0.1)
				(type default)
			)
			(layer "F.Fab")
		)
		(fp_line
			(start 0.8001 -0.40005)
			(end 0.8001 0.40005)
			(stroke
				(width 0.1)
				(type default)
			)
			(layer "F.Fab")
		)
		(fp_text user "+"
			(at -1.718564 -0.604266 180)
			(unlocked yes)
			(layer "F.SilkS")
			(effects
				(font
					(size 1.905 1.4224)
					(thickness 0.1524)
				)
				(justify left)
			)
		)
		(fp_text user "-"
			(at 0.472186 -1.029716 270)
			(unlocked yes)
			(layer "F.SilkS")
			(effects
				(font
					(size 1.905 1.4224)
					(thickness 0.1524)
				)
				(justify left)
			)
		)
		(fp_text user "+"
			(at -2.5654 -0.22225 270)
			(unlocked yes)
			(layer "F.Fab")
			(effects
				(font
					(size 1.905 1.4224)
					(thickness 0.1524)
				)
				(justify left)
			)
		)
		(fp_text user "-"
			(at 1.6256 -0.22225 270)
			(unlocked yes)
			(layer "F.Fab")
			(effects
				(font
					(size 1.905 1.4224)
					(thickness 0.1524)
				)
				(justify left)
			)
		)
		(pad "A" smd rect
			(at -0.750062 0 270)
			(size 0.8128 0.8128)
			(layers "F.Cu" "F.Mask" "F.Paste")
			(net "LED_POSTCODE_6_R")
		)
		(pad "C" smd rect
			(at 0.750062 0 270)
			(size 0.8128 0.8128)
			(layers "F.Cu" "F.Mask" "F.Paste")
			(net "GND")
		)
	)
	(footprint ""
		(layer "F.Cu")
		(at 14.351 -109.347 90)
		(property "Reference" "C272"
			(at 0 0 90)
			(layer "F.SilkS")
			(hide yes)
			(effects
				(font
					(size 1.27 1.27)
				)
			)
		)
		(property "Value" ""
			(at 0 0 90)
			(layer "F.Fab")
			(effects
				(font
					(size 1.27 1.27)
				)
			)
		)
		(duplicate_pad_numbers_are_jumpers no)
		(fp_line
			(start -0.4572 -0.4064)
			(end 0.381 -0.4064)
			(stroke
				(width 0.1524)
				(type default)
			)
			(layer "F.SilkS")
		)
		(fp_line
			(start 0.7874 0.0254)
			(end 0.7874 0.4064)
			(stroke
				(width 0.1524)
				(type default)
			)
			(layer "F.SilkS")
		)
		(fp_line
			(start 0.7874 0.4064)
			(end -0.7874 0.4064)
			(stroke
				(width 0.1524)
				(type default)
			)
			(layer "F.SilkS")
		)
		(fp_line
			(start -0.7874 0.4064)
			(end -0.7874 0.0254)
			(stroke
				(width 0.1524)
				(type default)
			)
			(layer "F.SilkS")
		)
		(fp_line
			(start -0.12065 -0.305054)
			(end -0.12065 -0.2794)
			(stroke
				(width 0.1)
				(type default)
			)
			(layer "F.Fab")
		)
		(fp_line
			(start -0.67945 -0.305054)
			(end -0.12065 -0.305054)
			(stroke
				(width 0.1)
				(type default)
			)
			(layer "F.Fab")
		)
		(fp_line
			(start 0.67945 -0.3048)
			(end 0.67945 0.3048)
			(stroke
				(width 0.1)
				(type default)
			)
			(layer "F.Fab")
		)
		(fp_line
			(start 0.12065 -0.3048)
			(end 0.67945 -0.3048)
			(stroke
				(width 0.1)
				(type default)
			)
			(layer "F.Fab")
		)
		(fp_line
			(start 0.12065 -0.2794)
			(end 0.12065 -0.3048)
			(stroke
				(width 0.1)
				(type default)
			)
			(layer "F.Fab")
		)
		(fp_line
			(start -0.12065 -0.2794)
			(end 0.12065 -0.2794)
			(stroke
				(width 0.1)
				(type default)
			)
			(layer "F.Fab")
		)
		(fp_line
			(start 0.120396 0.2794)
			(end -0.12065 0.2794)
			(stroke
				(width 0.1)
				(type default)
			)
			(layer "F.Fab")
		)
		(fp_line
			(start -0.12065 0.2794)
			(end -0.12065 0.3048)
			(stroke
				(width 0.1)
				(type default)
			)
			(layer "F.Fab")
		)
		(fp_line
			(start 0.67945 0.3048)
			(end 0.120396 0.3048)
			(stroke
				(width 0.1)
				(type default)
			)
			(layer "F.Fab")
		)
		(fp_line
			(start 0.120396 0.3048)
			(end 0.120396 0.2794)
			(stroke
				(width 0.1)
				(type default)
			)
			(layer "F.Fab")
		)
		(fp_line
			(start -0.12065 0.3048)
			(end -0.67945 0.3048)
			(stroke
				(width 0.1)
				(type default)
			)
			(layer "F.Fab")
		)
		(fp_line
			(start -0.67945 0.3048)
			(end -0.67945 -0.305054)
			(stroke
				(width 0.1)
				(type default)
			)
			(layer "F.Fab")
		)
		(pad "1" smd circle
			(at -0.40005 0 90)
			(size 0 0)
			(layers "F.Cu" "F.Mask" "F.Paste")
			(net "P2E_GPU_TX_DP")
		)
		(pad "2" smd circle
			(at 0.40005 0 90)
			(size 0 0)
			(layers "F.Cu" "F.Mask" "F.Paste")
			(net "P2E_GPU_TX_C_DP")
		)
	)
)
